(kicad_pcb
	(version 20260206)
	(generator "pcbnew")
	(generator_version "10.0")
	(general
		(thickness 1.6)
		(legacy_teardrops no)
	)
	(paper "A4")
	(title_block
		(title "01162023_DA0F0TEBIF0_F0T_Expander_BD_F_brd_V02_OCP.brd")
		(comment 1 "Grand Teton / footprints 4920-4926 of 9728")
	)
	(layers
		(0 "F.Cu" signal "TOP")
		(4 "In1.Cu" signal "GND")
		(6 "In2.Cu" signal "VCC")
		(8 "In3.Cu" signal "VCC1")
		(10 "In4.Cu" signal "GND1")
		(12 "In5.Cu" signal "IN1")
		(14 "In6.Cu" signal "GND2")
		(16 "In7.Cu" signal "IN2")
		(18 "In8.Cu" signal "GND3")
		(20 "In9.Cu" signal "IN3")
		(22 "In10.Cu" signal "GND4")
		(24 "In11.Cu" signal "IN4")
		(26 "In12.Cu" signal "GND5")
		(28 "In13.Cu" signal "IN5")
		(30 "In14.Cu" signal "GND6")
		(32 "In15.Cu" signal "IN6")
		(34 "In16.Cu" signal "GND7")
		(2 "B.Cu" signal "BOTTOM")
		(9 "F.Adhes" user "F.Adhesive")
		(11 "B.Adhes" user "B.Adhesive")
		(13 "F.Paste" user "Package Geometry/Pastemask Top")
		(15 "B.Paste" user "Package Geometry/Pastemask Bottom")
		(5 "F.SilkS" user "Ref Des/Silkscreen Top")
		(7 "B.SilkS" user "Ref Des/Silkscreen Bottom")
		(1 "F.Mask" user "Board Geometry/Soldermask Top")
		(3 "B.Mask" user "Board Geometry/Soldermask Bottom")
		(17 "Dwgs.User" user "User.Drawings")
		(19 "Cmts.User" user "User.Comments")
		(21 "Eco1.User" user "User.Eco1")
		(23 "Eco2.User" user "User.Eco2")
		(25 "Edge.Cuts" user "Board Geometry/Outline")
		(27 "Margin" user)
		(31 "F.CrtYd" user "Package Geometry/Place Bound Top")
		(29 "B.CrtYd" user "Package Geometry/Place Bound Bottom")
		(35 "F.Fab" user "Ref Des/Assembly Top")
		(33 "B.Fab" user "Ref Des/Assembly Bottom")
	)
	(footprint ""
		(layer "F.Cu")
		(at 4.682236 -393.746228 90)
		(property "Reference" "R6754"
			(at 0 0 90)
			(layer "F.SilkS")
			(hide yes)
			(effects
				(font
					(size 1.27 1.27)
				)
			)
		)
		(property "Value" ""
			(at 0 0 90)
			(layer "F.Fab")
			(effects
				(font
					(size 1.27 1.27)
				)
			)
		)
		(duplicate_pad_numbers_are_jumpers no)
		(fp_line
			(start 0.7874 -0.4064)
			(end 0.7874 0.4064)
			(stroke
				(width 0.1524)
				(type default)
			)
			(layer "F.SilkS")
		)
		(fp_line
			(start -0.7874 -0.4064)
			(end 0.7874 -0.4064)
			(stroke
				(width 0.1524)
				(type default)
			)
			(layer "F.SilkS")
		)
		(fp_line
			(start 0.7874 0.4064)
			(end -0.7874 0.4064)
			(stroke
				(width 0.1524)
				(type default)
			)
			(layer "F.SilkS")
		)
		(fp_line
			(start -0.7874 0.4064)
			(end -0.7874 -0.4064)
			(stroke
				(width 0.1524)
				(type default)
			)
			(layer "F.SilkS")
		)
		(fp_line
			(start -0.12065 -0.305054)
			(end -0.12065 -0.2794)
			(stroke
				(width 0.1)
				(type default)
			)
			(layer "F.Fab")
		)
		(fp_line
			(start -0.67945 -0.305054)
			(end -0.12065 -0.305054)
			(stroke
				(width 0.1)
				(type default)
			)
			(layer "F.Fab")
		)
		(fp_line
			(start 0.67945 -0.3048)
			(end 0.67945 0.3048)
			(stroke
				(width 0.1)
				(type default)
			)
			(layer "F.Fab")
		)
		(fp_line
			(start 0.12065 -0.3048)
			(end 0.67945 -0.3048)
			(stroke
				(width 0.1)
				(type default)
			)
			(layer "F.Fab")
		)
		(fp_line
			(start 0.12065 -0.2794)
			(end 0.12065 -0.3048)
			(stroke
				(width 0.1)
				(type default)
			)
			(layer "F.Fab")
		)
		(fp_line
			(start -0.12065 -0.2794)
			(end 0.12065 -0.2794)
			(stroke
				(width 0.1)
				(type default)
			)
			(layer "F.Fab")
		)
		(fp_line
			(start 0.120396 0.2794)
			(end -0.12065 0.2794)
			(stroke
				(width 0.1)
				(type default)
			)
			(layer "F.Fab")
		)
		(fp_line
			(start -0.12065 0.2794)
			(end -0.12065 0.3048)
			(stroke
				(width 0.1)
				(type default)
			)
			(layer "F.Fab")
		)
		(fp_line
			(start 0.67945 0.3048)
			(end 0.120396 0.3048)
			(stroke
				(width 0.1)
				(type default)
			)
			(layer "F.Fab")
		)
		(fp_line
			(start 0.120396 0.3048)
			(end 0.120396 0.2794)
			(stroke
				(width 0.1)
				(type default)
			)
			(layer "F.Fab")
		)
		(fp_line
			(start -0.12065 0.3048)
			(end -0.67945 0.3048)
			(stroke
				(width 0.1)
				(type default)
			)
			(layer "F.Fab")
		)
		(fp_line
			(start -0.67945 0.3048)
			(end -0.67945 -0.305054)
			(stroke
				(width 0.1)
				(type default)
			)
			(layer "F.Fab")
		)
		(pad "1" smd circle
			(at -0.40005 0 90)
			(size 0 0)
			(layers "F.Cu" "F.Mask" "F.Paste")
			(net "BIC_USB_8042_HUB_VBUS")
		)
		(pad "2" smd circle
			(at 0.40005 0 90)
			(size 0 0)
			(layers "F.Cu" "F.Mask" "F.Paste")
			(net "GND")
		)
	)
	(footprint ""
		(layer "F.Cu")
		(at 263.101836 -32.849312 90)
		(property "Reference" "R5682"
			(at 0 0 90)
			(layer "F.SilkS")
			(hide yes)
			(effects
				(font
					(size 1.27 1.27)
				)
			)
		)
		(property "Value" ""
			(at 0 0 90)
			(layer "F.Fab")
			(effects
				(font
					(size 1.27 1.27)
				)
			)
		)
		(duplicate_pad_numbers_are_jumpers no)
		(fp_line
			(start 0.7874 -0.4064)
			(end 0.7874 0.4064)
			(stroke
				(width 0.1524)
				(type default)
			)
			(layer "F.SilkS")
		)
		(fp_line
			(start -0.7874 -0.4064)
			(end 0.7874 -0.4064)
			(stroke
				(width 0.1524)
				(type default)
			)
			(layer "F.SilkS")
		)
		(fp_line
			(start 0.7874 0.4064)
			(end -0.7874 0.4064)
			(stroke
				(width 0.1524)
				(type default)
			)
			(layer "F.SilkS")
		)
		(fp_line
			(start -0.7874 0.4064)
			(end -0.7874 -0.4064)
			(stroke
				(width 0.1524)
				(type default)
			)
			(layer "F.SilkS")
		)
		(fp_line
			(start -0.12065 -0.305054)
			(end -0.12065 -0.2794)
			(stroke
				(width 0.1)
				(type default)
			)
			(layer "F.Fab")
		)
		(fp_line
			(start -0.67945 -0.305054)
			(end -0.12065 -0.305054)
			(stroke
				(width 0.1)
				(type default)
			)
			(layer "F.Fab")
		)
		(fp_line
			(start 0.67945 -0.3048)
			(end 0.67945 0.3048)
			(stroke
				(width 0.1)
				(type default)
			)
			(layer "F.Fab")
		)
		(fp_line
			(start 0.12065 -0.3048)
			(end 0.67945 -0.3048)
			(stroke
				(width 0.1)
				(type default)
			)
			(layer "F.Fab")
		)
		(fp_line
			(start 0.12065 -0.2794)
			(end 0.12065 -0.3048)
			(stroke
				(width 0.1)
				(type default)
			)
			(layer "F.Fab")
		)
		(fp_line
			(start -0.12065 -0.2794)
			(end 0.12065 -0.2794)
			(stroke
				(width 0.1)
				(type default)
			)
			(layer "F.Fab")
		)
		(fp_line
			(start 0.120396 0.2794)
			(end -0.12065 0.2794)
			(stroke
				(width 0.1)
				(type default)
			)
			(layer "F.Fab")
		)
		(fp_line
			(start -0.12065 0.2794)
			(end -0.12065 0.3048)
			(stroke
				(width 0.1)
				(type default)
			)
			(layer "F.Fab")
		)
		(fp_line
			(start 0.67945 0.3048)
			(end 0.120396 0.3048)
			(stroke
				(width 0.1)
				(type default)
			)
			(layer "F.Fab")
		)
		(fp_line
			(start 0.120396 0.3048)
			(end 0.120396 0.2794)
			(stroke
				(width 0.1)
				(type default)
			)
			(layer "F.Fab")
		)
		(fp_line
			(start -0.12065 0.3048)
			(end -0.67945 0.3048)
			(stroke
				(width 0.1)
				(type default)
			)
			(layer "F.Fab")
		)
		(fp_line
			(start -0.67945 0.3048)
			(end -0.67945 -0.305054)
			(stroke
				(width 0.1)
				(type default)
			)
			(layer "F.Fab")
		)
		(pad "1" smd circle
			(at -0.40005 0 90)
			(size 0 0)
			(layers "F.Cu" "F.Mask" "F.Paste")
			(net "RST_SMB_SSD9_ISO_R_N")
		)
		(pad "2" smd circle
			(at 0.40005 0 90)
			(size 0 0)
			(layers "F.Cu" "F.Mask" "F.Paste")
			(net "RST_SMB_SSD9_ISO_N")
		)
	)
	(footprint ""
		(layer "F.Cu")
		(at 93.350842 -356.244906 90)
		(property "Reference" "C160"
			(at 0 0 90)
			(layer "F.SilkS")
			(hide yes)
			(effects
				(font
					(size 1.27 1.27)
				)
			)
		)
		(property "Value" ""
			(at 0 0 90)
			(layer "F.Fab")
			(effects
				(font
					(size 1.27 1.27)
				)
			)
		)
		(duplicate_pad_numbers_are_jumpers no)
		(fp_line
			(start 0.299974 -0.150114)
			(end 0.299974 0.150114)
			(stroke
				(width 0.1)
				(type default)
			)
			(layer "F.Fab")
		)
		(fp_line
			(start -0.299974 -0.150114)
			(end 0.299974 -0.150114)
			(stroke
				(width 0.1)
				(type default)
			)
			(layer "F.Fab")
		)
		(fp_line
			(start 0.299974 0.150114)
			(end -0.299974 0.150114)
			(stroke
				(width 0.1)
				(type default)
			)
			(layer "F.Fab")
		)
		(fp_line
			(start -0.299974 0.150114)
			(end -0.299974 -0.150114)
			(stroke
				(width 0.1)
				(type default)
			)
			(layer "F.Fab")
		)
		(pad "1" smd rect
			(at -0.2667 0 90)
			(size 0.3048 0.381)
			(layers "F.Cu" "F.Mask" "F.Paste")
			(net "P5E_PEX0_STN6_TX_DN<96>")
		)
		(pad "2" smd rect
			(at 0.2667 0 90)
			(size 0.3048 0.381)
			(layers "F.Cu" "F.Mask" "F.Paste")
			(net "P5E_PEX0_STN6_TX_C_DN<96>")
		)
	)
	(footprint ""
		(layer "F.Cu")
		(at 393.798552 -66.32194 -90)
		(property "Reference" "PC881"
			(at 0 0 270)
			(layer "F.SilkS")
			(hide yes)
			(effects
				(font
					(size 1.27 1.27)
				)
			)
		)
		(property "Value" ""
			(at 0 0 270)
			(layer "F.Fab")
			(effects
				(font
					(size 1.27 1.27)
				)
			)
		)
		(duplicate_pad_numbers_are_jumpers no)
		(fp_line
			(start -0.7874 0.4064)
			(end -0.7874 -0.4064)
			(stroke
				(width 0.1524)
				(type default)
			)
			(layer "F.SilkS")
		)
		(fp_line
			(start 0.7874 0.4064)
			(end -0.7874 0.4064)
			(stroke
				(width 0.1524)
				(type default)
			)
			(layer "F.SilkS")
		)
		(fp_line
			(start -0.7874 -0.4064)
			(end 0.7874 -0.4064)
			(stroke
				(width 0.1524)
				(type default)
			)
			(layer "F.SilkS")
		)
		(fp_line
			(start 0.7874 -0.4064)
			(end 0.7874 0.4064)
			(stroke
				(width 0.1524)
				(type default)
			)
			(layer "F.SilkS")
		)
		(fp_line
			(start -0.67945 0.3048)
			(end -0.67945 -0.305054)
			(stroke
				(width 0.1)
				(type default)
			)
			(layer "F.Fab")
		)
		(fp_line
			(start -0.12065 0.3048)
			(end -0.67945 0.3048)
			(stroke
				(width 0.1)
				(type default)
			)
			(layer "F.Fab")
		)
		(fp_line
			(start 0.120396 0.3048)
			(end 0.120396 0.2794)
			(stroke
				(width 0.1)
				(type default)
			)
			(layer "F.Fab")
		)
		(fp_line
			(start 0.67945 0.3048)
			(end 0.120396 0.3048)
			(stroke
				(width 0.1)
				(type default)
			)
			(layer "F.Fab")
		)
		(fp_line
			(start -0.12065 0.2794)
			(end -0.12065 0.3048)
			(stroke
				(width 0.1)
				(type default)
			)
			(layer "F.Fab")
		)
		(fp_line
			(start 0.120396 0.2794)
			(end -0.12065 0.2794)
			(stroke
				(width 0.1)
				(type default)
			)
			(layer "F.Fab")
		)
		(fp_line
			(start -0.12065 -0.2794)
			(end 0.12065 -0.2794)
			(stroke
				(width 0.1)
				(type default)
			)
			(layer "F.Fab")
		)
		(fp_line
			(start 0.12065 -0.2794)
			(end 0.12065 -0.3048)
			(stroke
				(width 0.1)
				(type default)
			)
			(layer "F.Fab")
		)
		(fp_line
			(start 0.12065 -0.3048)
			(end 0.67945 -0.3048)
			(stroke
				(width 0.1)
				(type default)
			)
			(layer "F.Fab")
		)
		(fp_line
			(start 0.67945 -0.3048)
			(end 0.67945 0.3048)
			(stroke
				(width 0.1)
				(type default)
			)
			(layer "F.Fab")
		)
		(fp_line
			(start -0.67945 -0.305054)
			(end -0.12065 -0.305054)
			(stroke
				(width 0.1)
				(type default)
			)
			(layer "F.Fab")
		)
		(fp_line
			(start -0.12065 -0.305054)
			(end -0.12065 -0.2794)
			(stroke
				(width 0.1)
				(type default)
			)
			(layer "F.Fab")
		)
		(pad "1" smd circle
			(at -0.40005 0 270)
			(size 0 0)
			(layers "F.Cu" "F.Mask" "F.Paste")
			(net "P12V_SSD13_CO_GATE")
		)
		(pad "2" smd circle
			(at 0.40005 0 270)
			(size 0 0)
			(layers "F.Cu" "F.Mask" "F.Paste")
			(net "GND")
		)
	)
	(footprint ""
		(layer "F.Cu")
		(at 126.210314 -126.995428 180)
		(property "Reference" "PC482"
			(at 0 0 180)
			(layer "F.SilkS")
			(hide yes)
			(effects
				(font
					(size 1.27 1.27)
				)
			)
		)
		(property "Value" ""
			(at 0 0 180)
			(layer "F.Fab")
			(effects
				(font
					(size 1.27 1.27)
				)
			)
		)
		(duplicate_pad_numbers_are_jumpers no)
		(fp_line
			(start 0.7874 0.4064)
			(end -0.7874 0.4064)
			(stroke
				(width 0.1524)
				(type default)
			)
			(layer "F.SilkS")
		)
		(fp_line
			(start 0.7874 -0.4064)
			(end 0.7874 0.4064)
			(stroke
				(width 0.1524)
				(type default)
			)
			(layer "F.SilkS")
		)
		(fp_line
			(start -0.7874 0.4064)
			(end -0.7874 -0.4064)
			(stroke
				(width 0.1524)
				(type default)
			)
			(layer "F.SilkS")
		)
		(fp_line
			(start -0.7874 -0.4064)
			(end 0.7874 -0.4064)
			(stroke
				(width 0.1524)
				(type default)
			)
			(layer "F.SilkS")
		)
		(fp_line
			(start 0.67945 0.3048)
			(end 0.120396 0.3048)
			(stroke
				(width 0.1)
				(type default)
			)
			(layer "F.Fab")
		)
		(fp_line
			(start 0.67945 -0.3048)
			(end 0.67945 0.3048)
			(stroke
				(width 0.1)
				(type default)
			)
			(layer "F.Fab")
		)
		(fp_line
			(start 0.12065 -0.2794)
			(end 0.12065 -0.3048)
			(stroke
				(width 0.1)
				(type default)
			)
			(layer "F.Fab")
		)
		(fp_line
			(start 0.12065 -0.3048)
			(end 0.67945 -0.3048)
			(stroke
				(width 0.1)
				(type default)
			)
			(layer "F.Fab")
		)
		(fp_line
			(start 0.120396 0.3048)
			(end 0.120396 0.2794)
			(stroke
				(width 0.1)
				(type default)
			)
			(layer "F.Fab")
		)
		(fp_line
			(start 0.120396 0.2794)
			(end -0.12065 0.2794)
			(stroke
				(width 0.1)
				(type default)
			)
			(layer "F.Fab")
		)
		(fp_line
			(start -0.12065 0.3048)
			(end -0.67945 0.3048)
			(stroke
				(width 0.1)
				(type default)
			)
			(layer "F.Fab")
		)
		(fp_line
			(start -0.12065 0.2794)
			(end -0.12065 0.3048)
			(stroke
				(width 0.1)
				(type default)
			)
			(layer "F.Fab")
		)
		(fp_line
			(start -0.12065 -0.2794)
			(end 0.12065 -0.2794)
			(stroke
				(width 0.1)
				(type default)
			)
			(layer "F.Fab")
		)
		(fp_line
			(start -0.12065 -0.305054)
			(end -0.12065 -0.2794)
			(stroke
				(width 0.1)
				(type default)
			)
			(layer "F.Fab")
		)
		(fp_line
			(start -0.67945 0.3048)
			(end -0.67945 -0.305054)
			(stroke
				(width 0.1)
				(type default)
			)
			(layer "F.Fab")
		)
		(fp_line
			(start -0.67945 -0.305054)
			(end -0.12065 -0.305054)
			(stroke
				(width 0.1)
				(type default)
			)
			(layer "F.Fab")
		)
		(pad "1" smd circle
			(at -0.40005 0 180)
			(size 0 0)
			(layers "F.Cu" "F.Mask" "F.Paste")
			(net "P3V3_NIC2_SS")
		)
		(pad "2" smd circle
			(at 0.40005 0 180)
			(size 0 0)
			(layers "F.Cu" "F.Mask" "F.Paste")
			(net "GND")
		)
	)
	(footprint ""
		(layer "F.Cu")
		(at 278.68753 -25.342342 -90)
		(property "Reference" "R437"
			(at 0 0 270)
			(layer "F.SilkS")
			(hide yes)
			(effects
				(font
					(size 1.27 1.27)
				)
			)
		)
		(property "Value" ""
			(at 0 0 270)
			(layer "F.Fab")
			(effects
				(font
					(size 1.27 1.27)
				)
			)
		)
		(duplicate_pad_numbers_are_jumpers no)
		(fp_line
			(start -0.7874 0.4064)
			(end -0.7874 -0.4064)
			(stroke
				(width 0.1524)
				(type default)
			)
			(layer "F.SilkS")
		)
		(fp_line
			(start 0.7874 0.4064)
			(end -0.7874 0.4064)
			(stroke
				(width 0.1524)
				(type default)
			)
			(layer "F.SilkS")
		)
		(fp_line
			(start -0.7874 -0.4064)
			(end 0.7874 -0.4064)
			(stroke
				(width 0.1524)
				(type default)
			)
			(layer "F.SilkS")
		)
		(fp_line
			(start 0.7874 -0.4064)
			(end 0.7874 0.4064)
			(stroke
				(width 0.1524)
				(type default)
			)
			(layer "F.SilkS")
		)
		(fp_line
			(start -0.67945 0.3048)
			(end -0.67945 -0.305054)
			(stroke
				(width 0.1)
				(type default)
			)
			(layer "F.Fab")
		)
		(fp_line
			(start -0.12065 0.3048)
			(end -0.67945 0.3048)
			(stroke
				(width 0.1)
				(type default)
			)
			(layer "F.Fab")
		)
		(fp_line
			(start 0.120396 0.3048)
			(end 0.120396 0.2794)
			(stroke
				(width 0.1)
				(type default)
			)
			(layer "F.Fab")
		)
		(fp_line
			(start 0.67945 0.3048)
			(end 0.120396 0.3048)
			(stroke
				(width 0.1)
				(type default)
			)
			(layer "F.Fab")
		)
		(fp_line
			(start -0.12065 0.2794)
			(end -0.12065 0.3048)
			(stroke
				(width 0.1)
				(type default)
			)
			(layer "F.Fab")
		)
		(fp_line
			(start 0.120396 0.2794)
			(end -0.12065 0.2794)
			(stroke
				(width 0.1)
				(type default)
			)
			(layer "F.Fab")
		)
		(fp_line
			(start -0.12065 -0.2794)
			(end 0.12065 -0.2794)
			(stroke
				(width 0.1)
				(type default)
			)
			(layer "F.Fab")
		)
		(fp_line
			(start 0.12065 -0.2794)
			(end 0.12065 -0.3048)
			(stroke
				(width 0.1)
				(type default)
			)
			(layer "F.Fab")
		)
		(fp_line
			(start 0.12065 -0.3048)
			(end 0.67945 -0.3048)
			(stroke
				(width 0.1)
				(type default)
			)
			(layer "F.Fab")
		)
		(fp_line
			(start 0.67945 -0.3048)
			(end 0.67945 0.3048)
			(stroke
				(width 0.1)
				(type default)
			)
			(layer "F.Fab")
		)
		(fp_line
			(start -0.67945 -0.305054)
			(end -0.12065 -0.305054)
			(stroke
				(width 0.1)
				(type default)
			)
			(layer "F.Fab")
		)
		(fp_line
			(start -0.12065 -0.305054)
			(end -0.12065 -0.2794)
			(stroke
				(width 0.1)
				(type default)
			)
			(layer "F.Fab")
		)
		(pad "1" smd circle
			(at -0.40005 0 270)
			(size 0 0)
			(layers "F.Cu" "F.Mask" "F.Paste")
			(net "GND")
		)
		(pad "2" smd circle
			(at 0.40005 0 270)
			(size 0 0)
			(layers "F.Cu" "F.Mask" "F.Paste")
			(net "DUALPORT_N_SSD9")
		)
	)
	(footprint ""
		(layer "F.Cu")
		(at 457.180442 -373.719344 90)
		(property "Reference" "R6686"
			(at 0 0 90)
			(layer "F.SilkS")
			(hide yes)
			(effects
				(font
					(size 1.27 1.27)
				)
			)
		)
		(property "Value" ""
			(at 0 0 90)
			(layer "F.Fab")
			(effects
				(font
					(size 1.27 1.27)
				)
			)
		)
		(duplicate_pad_numbers_are_jumpers no)
		(fp_line
			(start 0.7874 -0.4064)
			(end 0.7874 0.4064)
			(stroke
				(width 0.1524)
				(type default)
			)
			(layer "F.SilkS")
		)
		(fp_line
			(start -0.7874 -0.4064)
			(end 0.7874 -0.4064)
			(stroke
				(width 0.1524)
				(type default)
			)
			(layer "F.SilkS")
		)
		(fp_line
			(start 0.7874 0.4064)
			(end -0.7874 0.4064)
			(stroke
				(width 0.1524)
				(type default)
			)
			(layer "F.SilkS")
		)
		(fp_line
			(start -0.7874 0.4064)
			(end -0.7874 -0.4064)
			(stroke
				(width 0.1524)
				(type default)
			)
			(layer "F.SilkS")
		)
		(fp_line
			(start -0.12065 -0.305054)
			(end -0.12065 -0.2794)
			(stroke
				(width 0.1)
				(type default)
			)
			(layer "F.Fab")
		)
		(fp_line
			(start -0.67945 -0.305054)
			(end -0.12065 -0.305054)
			(stroke
				(width 0.1)
				(type default)
			)
			(layer "F.Fab")
		)
		(fp_line
			(start 0.67945 -0.3048)
			(end 0.67945 0.3048)
			(stroke
				(width 0.1)
				(type default)
			)
			(layer "F.Fab")
		)
		(fp_line
			(start 0.12065 -0.3048)
			(end 0.67945 -0.3048)
			(stroke
				(width 0.1)
				(type default)
			)
			(layer "F.Fab")
		)
		(fp_line
			(start 0.12065 -0.2794)
			(end 0.12065 -0.3048)
			(stroke
				(width 0.1)
				(type default)
			)
			(layer "F.Fab")
		)
		(fp_line
			(start -0.12065 -0.2794)
			(end 0.12065 -0.2794)
			(stroke
				(width 0.1)
				(type default)
			)
			(layer "F.Fab")
		)
		(fp_line
			(start 0.120396 0.2794)
			(end -0.12065 0.2794)
			(stroke
				(width 0.1)
				(type default)
			)
			(layer "F.Fab")
		)
		(fp_line
			(start -0.12065 0.2794)
			(end -0.12065 0.3048)
			(stroke
				(width 0.1)
				(type default)
			)
			(layer "F.Fab")
		)
		(fp_line
			(start 0.67945 0.3048)
			(end 0.120396 0.3048)
			(stroke
				(width 0.1)
				(type default)
			)
			(layer "F.Fab")
		)
		(fp_line
			(start 0.120396 0.3048)
			(end 0.120396 0.2794)
			(stroke
				(width 0.1)
				(type default)
			)
			(layer "F.Fab")
		)
		(fp_line
			(start -0.12065 0.3048)
			(end -0.67945 0.3048)
			(stroke
				(width 0.1)
				(type default)
			)
			(layer "F.Fab")
		)
		(fp_line
			(start -0.67945 0.3048)
			(end -0.67945 -0.305054)
			(stroke
				(width 0.1)
				(type default)
			)
			(layer "F.Fab")
		)
		(pad "1" smd circle
			(at -0.40005 0 90)
			(size 0 0)
			(layers "F.Cu" "F.Mask" "F.Paste")
			(net "GPU_3V3IO_RSVD3_ISO_R")
		)
		(pad "2" smd circle
			(at 0.40005 0 90)
			(size 0 0)
			(layers "F.Cu" "F.Mask" "F.Paste")
			(net "GPU_3V3IO_RSVD3_ISO")
		)
	)
)
